FILE_TYPE = CONNECTIVITY;
{Allegro Design Entry HDL 17.4-2019 S026 (4007227) 1/17/2022}
"PAGE_NUMBER" = 258;
0"NC";
1"GND\g";
2"GND\g";
3"GND\g";
4"GND\g";
5"GND\g";
6"GND\g";
7"GND\g";
8"GND\g";
9"GND\g";
10"GND\g";
11"GND\g";
12"GND\g";
13"GND\g";
14"GND\g";
15"GND\g";
16"GND\g";
17"GND\g";
18"GND\g";
19"OCP_SFF_PRSNT1_R_N"CDS_PHYS_NET_NAME"OCP_SFF_PRSNT1_R_N";
20"P3V3_AUX\g";
21"OCP_V3_2_PRSNT01_R1_N";
22"OCP_V3_2_PRSNT23_R1_N";
23"OCP_SFF_PRSNT23_R1_N";
24"OCP_SFF_PRSNT01_R_N"CDS_PHYS_NET_NAME"OCP_SFF_PRSNT0_R_N";
25"P3V3_AUX\g";
26"P3V3_AUX\g";
27"P3V3_AUX\g";
28"P3V3_AUX\g";
29"P3V3_AUX\g";
30"P3V3_AUX\g";
31"OCP_SFF_PRSNT01_R1_N";
32"OCP_SFF_PRSNT23_R_N"CDS_PHYS_NET_NAME"OCP_SFF_PRSNT0_R_N";
33"OCP_V3_2_PRSNT01_R_N"CDS_PHYS_NET_NAME"OCP_SFF_PRSNT0_R_N";
34"OCP_V3_2_PRSNT23_R_N"CDS_PHYS_NET_NAME"OCP_SFF_PRSNT0_R_N";
35"OCP_SFF_PRSNT_ALL_R_N"CDS_PHYS_NET_NAME"OCP_SFF_PRSNT0_R_N";
36"OCP_V3_2_PRSNT_ALL_R_N"CDS_PHYS_NET_NAME"OCP_SFF_PRSNT0_R_N";
37"OCP_V3_2_PRSNT1_R_N"CDS_PHYS_NET_NAME"OCP_V3_2_PRSNT1_R_N";
38"OCP_SFF_PRSNT_ALL_R1_N";
39"OCP_SFF_RBT_ARB_IN_MUX2";
40"OCP_SFF_PRSNT3_R_N"CDS_PHYS_NET_NAME"OCP_SFF_PRSNT3_R_N";
41"OCP_SFF_PRSNT2_R_N"CDS_PHYS_NET_NAME"OCP_SFF_PRSNT2_R_N";
42"OCP_SFF_PRSNT0_R_N"CDS_PHYS_NET_NAME"OCP_SFF_PRSNT0_R_N";
43"OCP_V3_2_PRSNT2_R_N"CDS_PHYS_NET_NAME"OCP_V3_2_PRSNT2_R_N";
44"OCP_V3_2_PRSNT3_R_N"CDS_PHYS_NET_NAME"OCP_V3_2_PRSNT3_R_N";
45"OCP_V3_2_PRSNT0_R_N"CDS_PHYS_NET_NAME"OCP_V3_2_PRSNT0_R_N";
46"OCP_V3_2_RBT_ARB_OUT";
47"OCP_V3_2_RBT_ARB_IN";
48"OCP_SFF_RBT_ARB_IN_MUX1";
49"OCP_V3_2_PRSNT_ALL_R3_N";
50"OCP_SFF_RBT_ARB_IN_MUX2_R";
51"OCP_SFF_RBT_ARB_IN_MUX2";
52"OCP_SFF_RBT_ARB_IN_MUX1_R";
53"OCP_SFF_RBT_ARB_OUT";
54"OCP_SFF_RBT_ARB_IN";
55"OCP_SFF_NOT_PRSNT_RBT_ARB_IN";
56"OCP_SFF_PRSNT_ALL_R3_N";
57"OCP_SFF_RBT_ARB_IN_MUX1";
58"OCP_V3_2_PRSNT_ALL_R1_N";
59"OCP_V3_2_NOT_PRSNT_RBT_ARB_IN";
%"74LVC2G08DP"
"1","(-2600,750)","0","pure_quanta","I1";
;
LOCATION"U241"
$SEC"1"
CDS_SEC"1"
PART_TYPE"SMLF"
MATERIAL"EMPTY"
VALUE"74LVC2G08DP"
CDS_LIB"pure_quanta"
NEEDS_NO_SIZE"TRUE"
CDS_LMAN_SYM_OUTLINE"-150,100,150,-100"
PART_NUMBER"ALVC2G08K01";
"1Y"
$PN"7"33;
"1B"
$PN"2"37;
"1A"
$PN"1"45;
"GND"
$PN"4"4;
"VCC"
$PN"8"30;
%"74LVC2G08DP"
"1","(-2600,2850)","0","pure_quanta","I11";
;
LOCATION"U240"
$SEC"1"
CDS_SEC"1"
MATERIAL"EMPTY"
PART_TYPE"SMLF"
VALUE"74LVC2G08DP"
NEEDS_NO_SIZE"TRUE"
CDS_LMAN_SYM_OUTLINE"-150,100,150,-100"
CDS_LIB"pure_quanta"
PART_NUMBER"ALVC2G08K01";
"1Y"
$PN"7"24;
"1B"
$PN"2"19;
"1A"
$PN"1"42;
"GND"
$PN"4"3;
"VCC"
$PN"8"20;
%"74LVC2G08DP"
"2","(-2600,1950)","0","pure_quanta","I12";
;
LOCATION"U240"
$SEC"2"
CDS_SEC"2"
VALUE"74LVC2G08DP"
MATERIAL"EMPTY"
PART_TYPE"SMLF"
NEEDS_NO_SIZE"TRUE"
CDS_LMAN_SYM_OUTLINE"-150,100,150,-100"
CDS_LIB"pure_quanta"
PART_NUMBER"ALVC2G08K01";
"2Y"
$PN"3"32;
"2B"
$PN"6"40;
"2A"
$PN"5"41;
%"74LVC2G08DP"
"1","(-400,2400)","0","pure_quanta","I13";
;
LOCATION"U242"
$SEC"1"
CDS_SEC"1"
MATERIAL"EMPTY"
VALUE"74LVC2G08DP"
CDS_LIB"pure_quanta"
CDS_LMAN_SYM_OUTLINE"-150,100,150,-100"
NEEDS_NO_SIZE"TRUE"
PART_TYPE"SMLF"
PART_NUMBER"ALVC2G08K01";
"1Y"
$PN"7"35;
"1B"
$PN"2"23;
"1A"
$PN"1"31;
"GND"
$PN"4"10;
"VCC"
$PN"8"29;
%"74LVC2G08DP"
"2","(-400,275)","0","pure_quanta","I14";
;
LOCATION"U242"
$SEC"2"
CDS_SEC"2"
PART_TYPE"SMLF"
VALUE"74LVC2G08DP"
MATERIAL"EMPTY"
CDS_LIB"pure_quanta"
CDS_LMAN_SYM_OUTLINE"-150,100,150,-100"
NEEDS_NO_SIZE"TRUE"
PART_NUMBER"ALVC2G08K01";
"2Y"
$PN"3"36;
"2B"
$PN"6"22;
"2A"
$PN"5"21;
%"NC7SB3157"
"1","(2025,2400)","2","pure_quanta","I15";
;
LOCATION"U243"
$SEC"1"
CDS_SEC"1"
MATERIAL"EMPTY"
VALUE"NC7SB3157P6X"
CDS_LIB"pure_quanta"
CDS_LMAN_SYM_OUTLINE"-150,50,150,-150"
PACK_TYPE"SMLF"
MANUF_PN"NC7SB3157P6X"
PART_NUMBER"ALSB3157000";
"S"
$PN"6"38;
"B0"
$PN"3"53;
"B1"
$PN"1"55;
"VCC"
$PN"5"27;
"GND"
$PN"2"11;
"A"
$PN"4"39;
%"NC7SB3157"
"1","(2025,1550)","2","pure_quanta","I16";
;
LOCATION"U244"
$SEC"1"
CDS_SEC"1"
MATERIAL"EMPTY"
VALUE"NC7SB3157P6X"
PACK_TYPE"SMLF"
MANUF_PN"NC7SB3157P6X"
CDS_LMAN_SYM_OUTLINE"-150,50,150,-150"
CDS_LIB"pure_quanta"
PART_NUMBER"ALSB3157000";
"S"
$PN"6"56;
"B0"
$PN"3"54;
"B1"
$PN"1"55;
"VCC"
$PN"5"28;
"GND"
$PN"2"12;
"A"
$PN"4"52;
%"NC7SB3157"
"1","(2200,275)","2","pure_quanta","I17";
;
LOCATION"U246"
$SEC"1"
CDS_SEC"1"
VALUE"NC7SB3157P6X"
MATERIAL"EMPTY"
CDS_LIB"pure_quanta"
CDS_LMAN_SYM_OUTLINE"-150,50,150,-150"
PACK_TYPE"SMLF"
MANUF_PN"NC7SB3157P6X"
PART_NUMBER"ALSB3157000";
"S"
$PN"6"58;
"B0"
$PN"3"46;
"B1"
$PN"1"59;
"VCC"
$PN"5"25;
"GND"
$PN"2"13;
"A"
$PN"4"48;
%"NC7SB3157"
"1","(2175,-575)","2","pure_quanta","I18";
;
LOCATION"U245"
$SEC"1"
CDS_SEC"1"
MATERIAL"EMPTY"
VALUE"NC7SB3157P6X"
CDS_LIB"pure_quanta"
CDS_LMAN_SYM_OUTLINE"-150,50,150,-150"
PACK_TYPE"SMLF"
MANUF_PN"NC7SB3157P6X"
PART_NUMBER"ALSB3157000";
"S"
$PN"6"49;
"B0"
$PN"3"47;
"B1"
$PN"1"59;
"VCC"
$PN"5"26;
"GND"
$PN"2"14;
"A"
$PN"4"50;
%"UNIVERSAL_GND"
"1","(-2375,950)","0","pure_quanta_power","I19";
;
CDS_LIB"pure_quanta_power"
HDL_POWER"GND";
"A"1;
%"74LVC2G08DP"
"2","(-2600,-150)","0","pure_quanta","I2";
;
LOCATION"U241"
$SEC"2"
CDS_SEC"2"
MATERIAL"EMPTY"
PART_TYPE"SMLF"
VALUE"74LVC2G08DP"
CDS_LMAN_SYM_OUTLINE"-150,100,150,-100"
NEEDS_NO_SIZE"TRUE"
CDS_LIB"pure_quanta"
PART_NUMBER"ALVC2G08K01";
"2Y"
$PN"3"34;
"2B"
$PN"6"44;
"2A"
$PN"5"43;
%"UNIVERSAL_POWER"
"1","(-2375,1500)","0","pure_quanta_power","I20";
;
HDL_POWER"P3V3_AUX"
CDS_LIB"pure_quanta_power";
"A"30;
%"Q_CAP"
"1","(-2375,1175)","0","pure_quanta","I21";
;
LOCATION"C1875"
$SEC"1"
CDS_SEC"1"
PACK_TYPE"0402"
VALUE"0.1UF"
TOLERANCE"10%"
VOLTAGE"25V"
MATERIAL"X7R"
CDS_LIB"pure_quanta"
PART_NUMBER"CH4104K1B00";
"B"
$PN"2"1;
"A"
$PN"1"30;
%"Q_CAP"
"1","(-2475,3250)","0","pure_quanta","I22";
;
LOCATION"C1874"
$SEC"1"
CDS_SEC"1"
MATERIAL"X7R"
VALUE"0.1UF"
PACK_TYPE"0402"
VOLTAGE"25V"
TOLERANCE"10%"
CDS_LIB"pure_quanta"
PART_NUMBER"CH4104K1B00";
"B"
$PN"2"2;
"A"
$PN"1"20;
%"UNIVERSAL_POWER"
"1","(-2475,3575)","0","pure_quanta_power","I23";
;
HDL_POWER"P3V3_AUX"
CDS_LIB"pure_quanta_power";
"A"20;
%"UNIVERSAL_GND"
"1","(-2475,3025)","0","pure_quanta_power","I24";
;
CDS_LIB"pure_quanta_power"
HDL_POWER"GND";
"A"2;
%"UNIVERSAL_GND"
"1","(-2600,2575)","0","pure_quanta_power","I25";
;
CDS_LIB"pure_quanta_power"
HDL_POWER"GND";
"A"3;
%"UNIVERSAL_GND"
"1","(-2600,475)","0","pure_quanta_power","I26";
;
CDS_LIB"pure_quanta_power"
HDL_POWER"GND";
"A"4;
%"Q_CAP"
"1","(1525,575)","0","pure_quanta","I27";
;
LOCATION"C1880"
$SEC"1"
CDS_SEC"1"
PACK_TYPE"0402"
VALUE"0.1UF"
VOLTAGE"25V"
TOLERANCE"10%"
MATERIAL"X7R"
CDS_LIB"pure_quanta"
PART_NUMBER"CH4104K1B00";
"B"
$PN"2"5;
"A"
$PN"1"25;
%"UNIVERSAL_GND"
"1","(1525,350)","0","pure_quanta_power","I28";
;
CDS_LIB"pure_quanta_power"
HDL_POWER"GND";
"A"5;
%"UNIVERSAL_POWER"
"1","(1525,900)","0","pure_quanta_power","I29";
;
HDL_POWER"P3V3_AUX"
CDS_LIB"pure_quanta_power";
"A"25;
%"UNIVERSAL_POWER"
"1","(1525,25)","0","pure_quanta_power","I30";
;
HDL_POWER"P3V3_AUX"
CDS_LIB"pure_quanta_power";
"A"26;
%"Q_CAP"
"1","(1525,-250)","0","pure_quanta","I31";
;
LOCATION"C1879"
$SEC"1"
CDS_SEC"1"
VALUE"0.1UF"
TOLERANCE"10%"
MATERIAL"X7R"
PACK_TYPE"0402"
VOLTAGE"25V"
CDS_LIB"pure_quanta"
PART_NUMBER"CH4104K1B00";
"B"
$PN"2"6;
"A"
$PN"1"26;
%"UNIVERSAL_GND"
"1","(1525,-475)","0","pure_quanta_power","I32";
;
CDS_LIB"pure_quanta_power"
HDL_POWER"GND";
"A"6;
%"UNIVERSAL_POWER"
"1","(1325,3100)","0","pure_quanta_power","I33";
;
HDL_POWER"P3V3_AUX"
CDS_LIB"pure_quanta_power";
"A"27;
%"Q_CAP"
"1","(1325,2775)","0","pure_quanta","I34";
;
LOCATION"C1877"
$SEC"1"
CDS_SEC"1"
PACK_TYPE"0402"
VALUE"0.1UF"
VOLTAGE"25V"
TOLERANCE"10%"
MATERIAL"X7R"
CDS_LIB"pure_quanta"
PART_NUMBER"CH4104K1B00";
"B"
$PN"2"7;
"A"
$PN"1"27;
%"UNIVERSAL_GND"
"1","(1325,2550)","0","pure_quanta_power","I35";
;
CDS_LIB"pure_quanta_power"
HDL_POWER"GND";
"A"7;
%"UNIVERSAL_GND"
"1","(1350,1700)","0","pure_quanta_power","I36";
;
CDS_LIB"pure_quanta_power"
HDL_POWER"GND";
"A"8;
%"Q_CAP"
"1","(1350,1925)","0","pure_quanta","I37";
;
LOCATION"C1878"
$SEC"1"
CDS_SEC"1"
VALUE"0.1UF"
TOLERANCE"10%"
MATERIAL"X7R"
PACK_TYPE"0402"
VOLTAGE"25V"
CDS_LIB"pure_quanta"
PART_NUMBER"CH4104K1B00";
"B"
$PN"2"8;
"A"
$PN"1"28;
%"UNIVERSAL_POWER"
"1","(1350,2175)","0","pure_quanta_power","I38";
;
HDL_POWER"P3V3_AUX"
CDS_LIB"pure_quanta_power";
"A"28;
%"UNIVERSAL_GND"
"1","(-325,2625)","0","pure_quanta_power","I39";
;
CDS_LIB"pure_quanta_power"
HDL_POWER"GND";
"A"9;
%"UNIVERSAL_POWER"
"1","(-325,3175)","0","pure_quanta_power","I40";
;
HDL_POWER"P3V3_AUX"
CDS_LIB"pure_quanta_power";
"A"29;
%"Q_CAP"
"1","(-325,2850)","0","pure_quanta","I41";
;
LOCATION"C1876"
$SEC"1"
CDS_SEC"1"
MATERIAL"X7R"
PACK_TYPE"0402"
VALUE"0.1UF"
TOLERANCE"10%"
VOLTAGE"25V"
CDS_LIB"pure_quanta"
PART_NUMBER"CH4104K1B00";
"B"
$PN"2"9;
"A"
$PN"1"29;
%"UNIVERSAL_GND"
"1","(-400,2125)","0","pure_quanta_power","I42";
;
CDS_LIB"pure_quanta_power"
HDL_POWER"GND";
"A"10;
%"Q_RES"
"1","(825,2400)","0","pure_quanta","I44";
;
LOCATION"R3303"
$SEC"1"
CDS_SEC"1"
PACK_TYPE"0402LF"
MATERIAL"CHIP"
VALUE"0"
WATTAGE"1/16W"
TOLERANCE"5%"
CDS_LIB"pure_quanta"
PART_NUMBER"CS00002JB13";
"B"
$PN"2"38;
"A"
$PN"1"35;
%"Q_RES"
"1","(625,1550)","0","pure_quanta","I45";
;
LOCATION"R3304"
$SEC"1"
CDS_SEC"1"
MATERIAL"CHIP"
PACK_TYPE"0402LF"
WATTAGE"1/16W"
TOLERANCE"5%"
VALUE"0"
CDS_LIB"pure_quanta"
PART_NUMBER"CS00002JB13";
"B"
$PN"2"56;
"A"
$PN"1"35;
%"Q_RES"
"1","(825,275)","0","pure_quanta","I46";
;
LOCATION"R3308"
$SEC"1"
CDS_SEC"1"
MATERIAL"CHIP"
PACK_TYPE"0402LF"
TOLERANCE"5%"
WATTAGE"1/16W"
VALUE"0"
CDS_LIB"pure_quanta"
PART_NUMBER"CS00002JB13";
"B"
$PN"2"58;
"A"
$PN"1"36;
%"Q_RES"
"1","(800,-575)","0","pure_quanta","I47";
;
LOCATION"R3306"
$SEC"1"
CDS_SEC"1"
VALUE"0"
PACK_TYPE"0402LF"
MATERIAL"CHIP"
TOLERANCE"5%"
WATTAGE"1/16W"
CDS_LIB"pure_quanta"
PART_NUMBER"CS00002JB13";
"B"
$PN"2"49;
"A"
$PN"1"36;
%"Q_RES"
"1","(625,1450)","0","pure_quanta","I50";
;
LOCATION"R3305"
$SEC"1"
CDS_SEC"1"
MATERIAL"CHIP"
VALUE"0"
TOLERANCE"5%"
WATTAGE"1/16W"
PACK_TYPE"0402LF"
CDS_LIB"pure_quanta"
PART_NUMBER"CS00002JB13";
"B"
$PN"2"52;
"A"
$PN"1"57;
%"Q_RES"
"1","(800,-675)","0","pure_quanta","I52";
;
LOCATION"R3307"
$SEC"1"
CDS_SEC"1"
WATTAGE"1/16W"
VALUE"0"
MATERIAL"CHIP"
TOLERANCE"5%"
PACK_TYPE"0402LF"
CDS_LIB"pure_quanta"
PART_NUMBER"CS00002JB13";
"B"
$PN"2"50;
"A"
$PN"1"51;
%"UNIVERSAL_GND"
"1","(2375,2175)","0","pure_quanta_power","I60";
;
CDS_LIB"pure_quanta_power"
HDL_POWER"GND";
"A"11;
%"UNIVERSAL_GND"
"1","(2375,1325)","0","pure_quanta_power","I61";
;
CDS_LIB"pure_quanta_power"
HDL_POWER"GND";
"A"12;
%"UNIVERSAL_GND"
"1","(2550,50)","0","pure_quanta_power","I62";
;
CDS_LIB"pure_quanta_power"
HDL_POWER"GND";
"A"13;
%"UNIVERSAL_GND"
"1","(2525,-800)","0","pure_quanta_power","I63";
;
CDS_LIB"pure_quanta_power"
HDL_POWER"GND";
"A"14;
%"Q_RES"
"1","(-1450,2850)","0","pure_quanta","I64";
;
LOCATION"R8013"
SEC"1"
TOLERANCE"5%"
WATTAGE"1/16W"
MATERIAL"EMPTY"
PACK_TYPE"0402LF"
VALUE"0"
SEC_TYPE"0402LF"
CDS_LIB"pure_quanta"
PART_NUMBER"CS00002JB13";
"B"
$PN"2"31;
"A"
$PN"1"24;
%"Q_RES"
"1","(-1475,1950)","0","pure_quanta","I65";
;
LOCATION"R8014"
SEC"1"
MATERIAL"EMPTY"
TOLERANCE"5%"
WATTAGE"1/16W"
VALUE"0"
PACK_TYPE"0402LF"
CDS_LIB"pure_quanta"
SEC_TYPE"0402LF"
PART_NUMBER"CS00002JB13";
"B"
$PN"2"23;
"A"
$PN"1"32;
%"Q_RES"
"1","(-1450,750)","0","pure_quanta","I66";
;
LOCATION"R8015"
SEC"1"
VALUE"0"
WATTAGE"1/16W"
MATERIAL"EMPTY"
PACK_TYPE"0402LF"
TOLERANCE"5%"
CDS_LIB"pure_quanta"
SEC_TYPE"0402LF"
PART_NUMBER"CS00002JB13";
"B"
$PN"2"21;
"A"
$PN"1"33;
%"Q_RES"
"1","(-1475,-150)","0","pure_quanta","I67";
;
LOCATION"R8016"
SEC"1"
MATERIAL"EMPTY"
VALUE"0"
TOLERANCE"5%"
PACK_TYPE"0402LF"
WATTAGE"1/16W"
CDS_LIB"pure_quanta"
SEC_TYPE"0402LF"
PART_NUMBER"CS00002JB13";
"B"
$PN"2"22;
"A"
$PN"1"34;
%"Q_CAP"
"1","(-1200,2575)","2","pure_quanta","I68";
;
LOCATION"C8001"
SEC"1"
MATERIAL"EMPTY"
TOLERANCE"10%"
VALUE"0.1UF"
VOLTAGE"25V"
PACK_TYPE"0402"
CDS_LIB"pure_quanta"
SEC_TYPE"0402"
PART_NUMBER"CH4104K1B00";
"B"
$PN"2"15;
"A"
$PN"1"31;
%"UNIVERSAL_GND"
"1","(-1200,2300)","0","pure_quanta_power","I69";
;
CDS_LIB"pure_quanta_power"
HDL_POWER"GND";
"A"15;
%"Q_CAP"
"1","(-1200,1675)","2","pure_quanta","I70";
;
LOCATION"C8002"
$SEC"1"
CDS_SEC"1"
VALUE"0.1UF"
VOLTAGE"25V"
TOLERANCE"10%"
MATERIAL"EMPTY"
PACK_TYPE"0402"
CDS_LIB"pure_quanta"
PART_NUMBER"CH4104K1B00";
"B"
$PN"2"16;
"A"
$PN"1"23;
%"UNIVERSAL_GND"
"1","(-1200,1325)","0","pure_quanta_power","I71";
;
CDS_LIB"pure_quanta_power"
HDL_POWER"GND";
"A"16;
%"Q_CAP"
"1","(-1175,475)","2","pure_quanta","I72";
;
LOCATION"C8003"
$SEC"1"
CDS_SEC"1"
MATERIAL"EMPTY"
TOLERANCE"10%"
PACK_TYPE"0402"
VOLTAGE"25V"
VALUE"0.1UF"
CDS_LIB"pure_quanta"
PART_NUMBER"CH4104K1B00";
"B"
$PN"2"17;
"A"
$PN"1"21;
%"UNIVERSAL_GND"
"1","(-1175,125)","0","pure_quanta_power","I73";
;
CDS_LIB"pure_quanta_power"
HDL_POWER"GND";
"A"17;
%"Q_CAP"
"1","(-1175,-425)","2","pure_quanta","I74";
;
LOCATION"C8004"
$SEC"1"
CDS_SEC"1"
PACK_TYPE"0402"
VALUE"0.1UF"
VOLTAGE"25V"
MATERIAL"EMPTY"
TOLERANCE"10%"
CDS_LIB"pure_quanta"
PART_NUMBER"CH4104K1B00";
"B"
$PN"2"18;
"A"
$PN"1"22;
%"UNIVERSAL_GND"
"1","(-1175,-775)","0","pure_quanta_power","I75";
;
CDS_LIB"pure_quanta_power"
HDL_POWER"GND";
"A"18;
END.
